(kicad_pcb
	(version 20260206)
	(generator "pcbnew")
	(generator_version "10.0")
	(general
		(thickness 1.6)
		(legacy_teardrops no)
	)
	(paper "A4")
	(title_block
		(title "Bryce Canyon_IOM_M2_16342-2_OCP.brd")
		(comment 1 "Bryce Canyon / footprints 799-805 of 1146")
	)
	(layers
		(0 "F.Cu" signal "TOP")
		(4 "In1.Cu" signal "L2GND")
		(6 "In2.Cu" signal "L3")
		(8 "In3.Cu" signal "L4VCC")
		(10 "In4.Cu" signal "L5VCC")
		(12 "In5.Cu" signal "L6")
		(14 "In6.Cu" signal "L7GND")
		(2 "B.Cu" signal "BOTTOM")
		(9 "F.Adhes" user "F.Adhesive")
		(11 "B.Adhes" user "B.Adhesive")
		(13 "F.Paste" user "Package Geometry/Pastemask Top")
		(15 "B.Paste" user "Package Geometry/Pastemask Bottom")
		(5 "F.SilkS" user "Ref Des/Silkscreen Top")
		(7 "B.SilkS" user "Ref Des/Silkscreen Bottom")
		(1 "F.Mask" user "Board Geometry/Soldermask Top")
		(3 "B.Mask" user "Board Geometry/Soldermask Bottom")
		(17 "Dwgs.User" user "User.Drawings")
		(19 "Cmts.User" user "User.Comments")
		(21 "Eco1.User" user "User.Eco1")
		(23 "Eco2.User" user "User.Eco2")
		(25 "Edge.Cuts" user "Board Geometry/Outline")
		(27 "Margin" user)
		(31 "F.CrtYd" user "Package Geometry/Place Bound Top")
		(29 "B.CrtYd" user "Package Geometry/Place Bound Bottom")
		(35 "F.Fab" user "Ref Des/Assembly Top")
		(33 "B.Fab" user "Ref Des/Assembly Bottom")
	)
	(footprint ""
		(layer "B.Cu")
		(at 91.8972 -152.8318 180)
		(property "Reference" "C10"
			(at 0 0 0)
			(layer "B.SilkS")
			(hide yes)
			(effects
				(font
					(size 1.27 1.27)
				)
				(justify mirror)
			)
		)
		(property "Value" "SC1U16V2KX-7-GP"
			(at -1.7526 -1.6002 180)
			(unlocked yes)
			(layer "B.Fab")
			(hide yes)
			(effects
				(font
					(size 1.016 1.016)
					(thickness 0.1524)
				)
				(justify mirror)
			)
		)
		(property "Device Type" "C402-TO0D2H24"
			(at -1.7526 -3.1242 180)
			(unlocked yes)
			(layer "B.Fab")
			(hide yes)
			(effects
				(font
					(size 1.016 1.016)
					(thickness 0.1524)
				)
				(justify mirror)
			)
		)
		(duplicate_pad_numbers_are_jumpers no)
		(fp_rect
			(start 0.4826 0.889)
			(end -0.4826 -0.889)
			(stroke
				(width 0)
				(type default)
			)
			(fill no)
			(layer "B.CrtYd")
		)
		(fp_rect
			(start 0.4826 0.889)
			(end -0.4826 -0.889)
			(stroke
				(width 0)
				(type default)
			)
			(fill no)
			(layer "B.Fab")
		)
		(pad "1" smd custom
			(at 0 -0.4572)
			(size 0.1524 0.1524)
			(layers "B.Cu" "B.Mask" "B.Paste")
			(net "P3V3_STBY")
			(options
				(clearance outline)
				(anchor circle)
			)
			(primitives
				(gr_poly
					(pts
						(arc
							(start -0.254 -0.3048)
							(mid -0.325842 -0.275042)
							(end -0.3556 -0.2032)
						)
						(arc
							(start -0.3556 0.2032)
							(mid -0.325842 0.275042)
							(end -0.254 0.3048)
						)
						(arc
							(start 0.254 0.3048)
							(mid 0.325842 0.275042)
							(end 0.3556 0.2032)
						)
						(arc
							(start 0.3556 -0.2032)
							(mid 0.325842 -0.275042)
							(end 0.254 -0.3048)
						)
					)
					(width 0)
					(fill yes)
				)
			)
		)
		(pad "2" smd custom
			(at 0 0.4572)
			(size 0.1524 0.1524)
			(layers "B.Cu" "B.Mask" "B.Paste")
			(net "GND")
			(options
				(clearance outline)
				(anchor circle)
			)
			(primitives
				(gr_poly
					(pts
						(arc
							(start -0.254 -0.3048)
							(mid -0.325842 -0.275042)
							(end -0.3556 -0.2032)
						)
						(arc
							(start -0.3556 0.2032)
							(mid -0.325842 0.275042)
							(end -0.254 0.3048)
						)
						(arc
							(start 0.254 0.3048)
							(mid 0.325842 0.275042)
							(end 0.3556 0.2032)
						)
						(arc
							(start 0.3556 -0.2032)
							(mid 0.325842 -0.275042)
							(end 0.254 -0.3048)
						)
					)
					(width 0)
					(fill yes)
				)
			)
		)
	)
	(footprint ""
		(layer "B.Cu")
		(at 60.2488 -151.765 90)
		(property "Reference" "R393"
			(at 0 0 90)
			(layer "B.SilkS")
			(hide yes)
			(effects
				(font
					(size 1.27 1.27)
				)
				(justify mirror)
			)
		)
		(property "Value" "4K7R2F-GP"
			(at -0.064008 -3.993896 90)
			(unlocked yes)
			(layer "B.Fab")
			(hide yes)
			(effects
				(font
					(size 1.016 1.016)
					(thickness 0.1524)
				)
				(justify mirror)
			)
		)
		(property "Device Type" "R402H16"
			(at -0.064008 -5.517896 90)
			(unlocked yes)
			(layer "B.Fab")
			(hide yes)
			(effects
				(font
					(size 1.016 1.016)
					(thickness 0.1524)
				)
				(justify mirror)
			)
		)
		(duplicate_pad_numbers_are_jumpers no)
		(fp_line
			(start 0.508 -0.9398)
			(end 0.508 0.9398)
			(stroke
				(width 0.1524)
				(type default)
			)
			(layer "B.SilkS")
		)
		(fp_line
			(start -0.508 -0.9398)
			(end 0.508 -0.9398)
			(stroke
				(width 0.1524)
				(type default)
			)
			(layer "B.SilkS")
		)
		(fp_rect
			(start 0.508 0.9398)
			(end -0.508 -0.9398)
			(stroke
				(width 0)
				(type default)
			)
			(fill no)
			(layer "B.CrtYd")
		)
		(fp_rect
			(start 0.508 0.9398)
			(end -0.508 -0.9398)
			(stroke
				(width 0)
				(type default)
			)
			(fill no)
			(layer "B.Fab")
		)
		(pad "1" smd custom
			(at 0 -0.4445 270)
			(size 0.1397 0.1397)
			(layers "B.Cu" "B.Mask" "B.Paste")
			(net "P3V3_STBY")
			(options
				(clearance outline)
				(anchor circle)
			)
			(primitives
				(gr_poly
					(pts
						(arc
							(start -0.1778 0.2794)
							(mid -0.249642 0.249642)
							(end -0.2794 0.1778)
						)
						(arc
							(start -0.2794 -0.1778)
							(mid -0.249642 -0.249642)
							(end -0.1778 -0.2794)
						)
						(arc
							(start 0.1778 -0.2794)
							(mid 0.249642 -0.249642)
							(end 0.2794 -0.1778)
						)
						(arc
							(start 0.2794 0.1778)
							(mid 0.249642 0.249642)
							(end 0.1778 0.2794)
						)
					)
					(width 0)
					(fill yes)
				)
			)
		)
		(pad "2" smd custom
			(at 0 0.4445 270)
			(size 0.1397 0.1397)
			(layers "B.Cu" "B.Mask" "B.Paste")
			(net "MAC2_TXD2")
			(options
				(clearance outline)
				(anchor circle)
			)
			(primitives
				(gr_poly
					(pts
						(arc
							(start -0.1778 0.2794)
							(mid -0.249642 0.249642)
							(end -0.2794 0.1778)
						)
						(arc
							(start -0.2794 -0.1778)
							(mid -0.249642 -0.249642)
							(end -0.1778 -0.2794)
						)
						(arc
							(start 0.1778 -0.2794)
							(mid 0.249642 -0.249642)
							(end 0.2794 -0.1778)
						)
						(arc
							(start 0.2794 0.1778)
							(mid 0.249642 0.249642)
							(end 0.1778 0.2794)
						)
					)
					(width 0)
					(fill yes)
				)
			)
		)
	)
	(footprint ""
		(layer "B.Cu")
		(at 93.372686 -129.463546 -90)
		(property "Reference" "C126"
			(at 0 0 90)
			(layer "B.SilkS")
			(hide yes)
			(effects
				(font
					(size 1.27 1.27)
				)
				(justify mirror)
			)
		)
		(property "Value" "SCD1U16V2KX-3GP"
			(at -1.1811 -2.7051 270)
			(unlocked yes)
			(layer "B.Fab")
			(hide yes)
			(effects
				(font
					(size 1.016 1.016)
					(thickness 0.1524)
				)
				(justify mirror)
			)
		)
		(property "Device Type" "C402H22"
			(at -1.1811 -4.2291 270)
			(unlocked yes)
			(layer "B.Fab")
			(hide yes)
			(effects
				(font
					(size 1.016 1.016)
					(thickness 0.1524)
				)
				(justify mirror)
			)
		)
		(duplicate_pad_numbers_are_jumpers no)
		(fp_rect
			(start 0.4318 0.9525)
			(end -0.4318 -0.9525)
			(stroke
				(width 0)
				(type default)
			)
			(fill no)
			(layer "B.CrtYd")
		)
		(fp_rect
			(start 0.4318 0.9525)
			(end -0.4318 -0.9525)
			(stroke
				(width 0)
				(type default)
			)
			(fill no)
			(layer "B.Fab")
		)
		(pad "1" smd custom
			(at 0 -0.4445 90)
			(size 0.1524 0.1524)
			(layers "B.Cu" "B.Mask" "B.Paste")
			(net "P3V3_STBY")
			(options
				(clearance outline)
				(anchor circle)
			)
			(primitives
				(gr_poly
					(pts
						(arc
							(start 0.3048 0.2032)
							(mid 0.275042 0.275042)
							(end 0.2032 0.3048)
						)
						(arc
							(start -0.2032 0.3048)
							(mid -0.275042 0.275042)
							(end -0.3048 0.2032)
						)
						(arc
							(start -0.3048 -0.2032)
							(mid -0.275042 -0.275042)
							(end -0.2032 -0.3048)
						)
						(arc
							(start 0.2032 -0.3048)
							(mid 0.275042 -0.275042)
							(end 0.3048 -0.2032)
						)
					)
					(width 0)
					(fill yes)
				)
			)
		)
		(pad "2" smd custom
			(at 0 0.4445 90)
			(size 0.1524 0.1524)
			(layers "B.Cu" "B.Mask" "B.Paste")
			(net "GND")
			(options
				(clearance outline)
				(anchor circle)
			)
			(primitives
				(gr_poly
					(pts
						(arc
							(start 0.3048 0.2032)
							(mid 0.275042 0.275042)
							(end 0.2032 0.3048)
						)
						(arc
							(start -0.2032 0.3048)
							(mid -0.275042 0.275042)
							(end -0.3048 0.2032)
						)
						(arc
							(start -0.3048 -0.2032)
							(mid -0.275042 -0.275042)
							(end -0.2032 -0.3048)
						)
						(arc
							(start 0.2032 -0.3048)
							(mid 0.275042 -0.275042)
							(end 0.3048 -0.2032)
						)
					)
					(width 0)
					(fill yes)
				)
			)
		)
	)
	(footprint ""
		(layer "B.Cu")
		(at 22.225 -173.0756 90)
		(property "Reference" "C999"
			(at 0 0 90)
			(layer "B.SilkS")
			(hide yes)
			(effects
				(font
					(size 1.27 1.27)
				)
				(justify mirror)
			)
		)
		(property "Value" "SCD1U16V2KX-3GP"
			(at -1.1811 -2.7051 90)
			(unlocked yes)
			(layer "B.Fab")
			(hide yes)
			(effects
				(font
					(size 1.016 1.016)
					(thickness 0.1524)
				)
				(justify mirror)
			)
		)
		(property "Device Type" "C402H22"
			(at -1.1811 -4.2291 90)
			(unlocked yes)
			(layer "B.Fab")
			(hide yes)
			(effects
				(font
					(size 1.016 1.016)
					(thickness 0.1524)
				)
				(justify mirror)
			)
		)
		(duplicate_pad_numbers_are_jumpers no)
		(fp_rect
			(start 0.4318 0.9525)
			(end -0.4318 -0.9525)
			(stroke
				(width 0)
				(type default)
			)
			(fill no)
			(layer "B.CrtYd")
		)
		(fp_rect
			(start 0.4318 0.9525)
			(end -0.4318 -0.9525)
			(stroke
				(width 0)
				(type default)
			)
			(fill no)
			(layer "B.Fab")
		)
		(pad "1" smd custom
			(at 0 -0.4445 270)
			(size 0.1524 0.1524)
			(layers "B.Cu" "B.Mask" "B.Paste")
			(net "P1V8_STBY")
			(options
				(clearance outline)
				(anchor circle)
			)
			(primitives
				(gr_poly
					(pts
						(arc
							(start 0.3048 0.2032)
							(mid 0.275042 0.275042)
							(end 0.2032 0.3048)
						)
						(arc
							(start -0.2032 0.3048)
							(mid -0.275042 0.275042)
							(end -0.3048 0.2032)
						)
						(arc
							(start -0.3048 -0.2032)
							(mid -0.275042 -0.275042)
							(end -0.2032 -0.3048)
						)
						(arc
							(start 0.2032 -0.3048)
							(mid 0.275042 -0.275042)
							(end 0.3048 -0.2032)
						)
					)
					(width 0)
					(fill yes)
				)
			)
		)
		(pad "2" smd custom
			(at 0 0.4445 270)
			(size 0.1524 0.1524)
			(layers "B.Cu" "B.Mask" "B.Paste")
			(net "GND")
			(options
				(clearance outline)
				(anchor circle)
			)
			(primitives
				(gr_poly
					(pts
						(arc
							(start 0.3048 0.2032)
							(mid 0.275042 0.275042)
							(end 0.2032 0.3048)
						)
						(arc
							(start -0.2032 0.3048)
							(mid -0.275042 0.275042)
							(end -0.3048 0.2032)
						)
						(arc
							(start -0.3048 -0.2032)
							(mid -0.275042 -0.275042)
							(end -0.2032 -0.3048)
						)
						(arc
							(start 0.2032 -0.3048)
							(mid 0.275042 -0.275042)
							(end 0.3048 -0.2032)
						)
					)
					(width 0)
					(fill yes)
				)
			)
		)
	)
	(footprint ""
		(layer "B.Cu")
		(at 93.84792 -158.555944)
		(property "Reference" "C11"
			(at 0 0 0)
			(layer "B.SilkS")
			(hide yes)
			(effects
				(font
					(size 1.27 1.27)
				)
				(justify mirror)
			)
		)
		(property "Value" "SC1U16V2KX-7-GP"
			(at -1.7526 -1.6002 0)
			(unlocked yes)
			(layer "B.Fab")
			(hide yes)
			(effects
				(font
					(size 1.016 1.016)
					(thickness 0.1524)
				)
				(justify mirror)
			)
		)
		(property "Device Type" "C402-TO0D2H24"
			(at -1.7526 -3.1242 0)
			(unlocked yes)
			(layer "B.Fab")
			(hide yes)
			(effects
				(font
					(size 1.016 1.016)
					(thickness 0.1524)
				)
				(justify mirror)
			)
		)
		(duplicate_pad_numbers_are_jumpers no)
		(fp_rect
			(start 0.4826 0.889)
			(end -0.4826 -0.889)
			(stroke
				(width 0)
				(type default)
			)
			(fill no)
			(layer "B.CrtYd")
		)
		(fp_rect
			(start 0.4826 0.889)
			(end -0.4826 -0.889)
			(stroke
				(width 0)
				(type default)
			)
			(fill no)
			(layer "B.Fab")
		)
		(pad "1" smd custom
			(at 0 -0.4572 180)
			(size 0.1524 0.1524)
			(layers "B.Cu" "B.Mask" "B.Paste")
			(net "P3V3_STBY")
			(options
				(clearance outline)
				(anchor circle)
			)
			(primitives
				(gr_poly
					(pts
						(arc
							(start -0.254 -0.3048)
							(mid -0.325842 -0.275042)
							(end -0.3556 -0.2032)
						)
						(arc
							(start -0.3556 0.2032)
							(mid -0.325842 0.275042)
							(end -0.254 0.3048)
						)
						(arc
							(start 0.254 0.3048)
							(mid 0.325842 0.275042)
							(end 0.3556 0.2032)
						)
						(arc
							(start 0.3556 -0.2032)
							(mid 0.325842 -0.275042)
							(end 0.254 -0.3048)
						)
					)
					(width 0)
					(fill yes)
				)
			)
		)
		(pad "2" smd custom
			(at 0 0.4572 180)
			(size 0.1524 0.1524)
			(layers "B.Cu" "B.Mask" "B.Paste")
			(net "GND")
			(options
				(clearance outline)
				(anchor circle)
			)
			(primitives
				(gr_poly
					(pts
						(arc
							(start -0.254 -0.3048)
							(mid -0.325842 -0.275042)
							(end -0.3556 -0.2032)
						)
						(arc
							(start -0.3556 0.2032)
							(mid -0.325842 0.275042)
							(end -0.254 0.3048)
						)
						(arc
							(start 0.254 0.3048)
							(mid 0.325842 0.275042)
							(end 0.3556 0.2032)
						)
						(arc
							(start 0.3556 -0.2032)
							(mid 0.325842 -0.275042)
							(end 0.254 -0.3048)
						)
					)
					(width 0)
					(fill yes)
				)
			)
		)
	)
	(footprint ""
		(layer "B.Cu")
		(at 67.818 -148.463 -90)
		(property "Reference" "R334"
			(at 0 0 90)
			(layer "B.SilkS")
			(hide yes)
			(effects
				(font
					(size 1.27 1.27)
				)
				(justify mirror)
			)
		)
		(property "Value" "0R2J-2-GP"
			(at -0.064008 -3.993896 270)
			(unlocked yes)
			(layer "B.Fab")
			(hide yes)
			(effects
				(font
					(size 1.016 1.016)
					(thickness 0.1524)
				)
				(justify mirror)
			)
		)
		(property "Device Type" "R402H16"
			(at -0.064008 -5.517896 270)
			(unlocked yes)
			(layer "B.Fab")
			(hide yes)
			(effects
				(font
					(size 1.016 1.016)
					(thickness 0.1524)
				)
				(justify mirror)
			)
		)
		(duplicate_pad_numbers_are_jumpers no)
		(fp_line
			(start -0.508 -0.9398)
			(end 0.508 -0.9398)
			(stroke
				(width 0.1524)
				(type default)
			)
			(layer "B.SilkS")
		)
		(fp_line
			(start 0.508 -0.9398)
			(end 0.508 0.9398)
			(stroke
				(width 0.1524)
				(type default)
			)
			(layer "B.SilkS")
		)
		(fp_rect
			(start 0.508 0.9398)
			(end -0.508 -0.9398)
			(stroke
				(width 0)
				(type default)
			)
			(fill no)
			(layer "B.CrtYd")
		)
		(fp_rect
			(start 0.508 0.9398)
			(end -0.508 -0.9398)
			(stroke
				(width 0)
				(type default)
			)
			(fill no)
			(layer "B.Fab")
		)
		(pad "1" smd custom
			(at 0 -0.4445 90)
			(size 0.1397 0.1397)
			(layers "B.Cu" "B.Mask" "B.Paste")
			(net "NCSI_TXD0")
			(options
				(clearance outline)
				(anchor circle)
			)
			(primitives
				(gr_poly
					(pts
						(arc
							(start -0.1778 0.2794)
							(mid -0.249642 0.249642)
							(end -0.2794 0.1778)
						)
						(arc
							(start -0.2794 -0.1778)
							(mid -0.249642 -0.249642)
							(end -0.1778 -0.2794)
						)
						(arc
							(start 0.1778 -0.2794)
							(mid 0.249642 -0.249642)
							(end 0.2794 -0.1778)
						)
						(arc
							(start 0.2794 0.1778)
							(mid 0.249642 0.249642)
							(end 0.1778 0.2794)
						)
					)
					(width 0)
					(fill yes)
				)
			)
		)
		(pad "2" smd custom
			(at 0 0.4445 90)
			(size 0.1397 0.1397)
			(layers "B.Cu" "B.Mask" "B.Paste")
			(net "NCSI_TXD0_R")
			(options
				(clearance outline)
				(anchor circle)
			)
			(primitives
				(gr_poly
					(pts
						(arc
							(start -0.1778 0.2794)
							(mid -0.249642 0.249642)
							(end -0.2794 0.1778)
						)
						(arc
							(start -0.2794 -0.1778)
							(mid -0.249642 -0.249642)
							(end -0.1778 -0.2794)
						)
						(arc
							(start 0.1778 -0.2794)
							(mid 0.249642 -0.249642)
							(end 0.2794 -0.1778)
						)
						(arc
							(start 0.2794 0.1778)
							(mid 0.249642 0.249642)
							(end 0.1778 0.2794)
						)
					)
					(width 0)
					(fill yes)
				)
			)
		)
	)
	(footprint ""
		(layer "B.Cu")
		(at 49.6316 -134.239 90)
		(property "Reference" "R599"
			(at 0 0 90)
			(layer "B.SilkS")
			(hide yes)
			(effects
				(font
					(size 1.27 1.27)
				)
				(justify mirror)
			)
		)
		(property "Value" "4K7R2F-GP"
			(at -0.064008 -3.993896 90)
			(unlocked yes)
			(layer "B.Fab")
			(hide yes)
			(effects
				(font
					(size 1.016 1.016)
					(thickness 0.1524)
				)
				(justify mirror)
			)
		)
		(property "Device Type" "R402H16"
			(at -0.064008 -5.517896 90)
			(unlocked yes)
			(layer "B.Fab")
			(hide yes)
			(effects
				(font
					(size 1.016 1.016)
					(thickness 0.1524)
				)
				(justify mirror)
			)
		)
		(duplicate_pad_numbers_are_jumpers no)
		(fp_line
			(start 0.508 -0.9398)
			(end 0.508 0.9398)
			(stroke
				(width 0.1524)
				(type default)
			)
			(layer "B.SilkS")
		)
		(fp_line
			(start -0.508 -0.9398)
			(end 0.508 -0.9398)
			(stroke
				(width 0.1524)
				(type default)
			)
			(layer "B.SilkS")
		)
		(fp_rect
			(start 0.508 0.9398)
			(end -0.508 -0.9398)
			(stroke
				(width 0)
				(type default)
			)
			(fill no)
			(layer "B.CrtYd")
		)
		(fp_rect
			(start 0.508 0.9398)
			(end -0.508 -0.9398)
			(stroke
				(width 0)
				(type default)
			)
			(fill no)
			(layer "B.Fab")
		)
		(pad "1" smd custom
			(at 0 -0.4445 270)
			(size 0.1397 0.1397)
			(layers "B.Cu" "B.Mask" "B.Paste")
			(net "P3V3_STBY")
			(options
				(clearance outline)
				(anchor circle)
			)
			(primitives
				(gr_poly
					(pts
						(arc
							(start -0.1778 0.2794)
							(mid -0.249642 0.249642)
							(end -0.2794 0.1778)
						)
						(arc
							(start -0.2794 -0.1778)
							(mid -0.249642 -0.249642)
							(end -0.1778 -0.2794)
						)
						(arc
							(start 0.1778 -0.2794)
							(mid 0.249642 -0.249642)
							(end 0.2794 -0.1778)
						)
						(arc
							(start 0.2794 0.1778)
							(mid 0.249642 0.249642)
							(end 0.1778 0.2794)
						)
					)
					(width 0)
					(fill yes)
				)
			)
		)
		(pad "2" smd custom
			(at 0 0.4445 270)
			(size 0.1397 0.1397)
			(layers "B.Cu" "B.Mask" "B.Paste")
			(net "DPB_MISC_ALERT_OUT")
			(options
				(clearance outline)
				(anchor circle)
			)
			(primitives
				(gr_poly
					(pts
						(arc
							(start -0.1778 0.2794)
							(mid -0.249642 0.249642)
							(end -0.2794 0.1778)
						)
						(arc
							(start -0.2794 -0.1778)
							(mid -0.249642 -0.249642)
							(end -0.1778 -0.2794)
						)
						(arc
							(start 0.1778 -0.2794)
							(mid 0.249642 -0.249642)
							(end 0.2794 -0.1778)
						)
						(arc
							(start 0.2794 0.1778)
							(mid 0.249642 0.249642)
							(end 0.1778 0.2794)
						)
					)
					(width 0)
					(fill yes)
				)
			)
		)
	)
)
